(kicad_pcb
	(version 20260206)
	(generator "pcbnew")
	(generator_version "10.0")
	(general
		(thickness 1.6)
		(legacy_teardrops no)
	)
	(paper "A4")
	(title_block
		(title "peb — Lightning_PEB_BRD.brd")
		(comment 1 "Lightning (Wiwynn / Facebook NVMe JBOF) / footprint 1445 of 2563 (U1), pads 585-698 of 1311")
	)
	(layers
		(0 "F.Cu" signal "TOP")
		(4 "In1.Cu" signal "L2GND")
		(6 "In2.Cu" signal "L3")
		(8 "In3.Cu" signal "L4VCC")
		(10 "In4.Cu" signal "L5VCC")
		(12 "In5.Cu" signal "L6")
		(14 "In6.Cu" signal "L7GND")
		(2 "B.Cu" signal "BOTTOM")
		(9 "F.Adhes" user "F.Adhesive")
		(11 "B.Adhes" user "B.Adhesive")
		(13 "F.Paste" user "Package Geometry/Pastemask Top")
		(15 "B.Paste" user "Package Geometry/Pastemask Bottom")
		(5 "F.SilkS" user "Ref Des/Silkscreen Top")
		(7 "B.SilkS" user "Ref Des/Silkscreen Bottom")
		(1 "F.Mask" user "Board Geometry/Soldermask Top")
		(3 "B.Mask" user "Board Geometry/Soldermask Bottom")
		(17 "Dwgs.User" user "User.Drawings")
		(19 "Cmts.User" user "User.Comments")
		(21 "Eco1.User" user "User.Eco1")
		(23 "Eco2.User" user "User.Eco2")
		(25 "Edge.Cuts" user "Board Geometry/Outline")
		(27 "Margin" user)
		(31 "F.CrtYd" user "Package Geometry/Place Bound Top")
		(29 "B.CrtYd" user "Package Geometry/Place Bound Bottom")
		(35 "F.Fab" user "Ref Des/Assembly Top")
		(33 "B.Fab" user "Ref Des/Assembly Bottom")
	)
	(footprint ""
		(layer "F.Cu")
		(at 240.599976 -47.999904 -90)
		(property "Reference" "U1"
			(at 0 0 270)
			(layer "F.SilkS")
			(hide yes)
			(effects
				(font
					(size 1.27 1.27)
				)
			)
		)
		(property "Value" "PM8546A-FEIP-GP"
			(at -25.785064 -6.40334 270)
			(unlocked yes)
			(layer "F.Fab")
			(hide yes)
			(effects
				(font
					(size 1.016 1.016)
					(thickness 0.1524)
				)
			)
		)
		(property "Device Type" "BGA1311C37D5H134"
			(at -25.785064 -7.92734 270)
			(unlocked yes)
			(layer "F.Fab")
			(hide yes)
			(effects
				(font
					(size 1.016 1.016)
					(thickness 0.1524)
				)
			)
		)
		(duplicate_pad_numbers_are_jumpers no)
		(pad "AT21" smd circle
			(at 1.999996 16.999966 270)
			(size 0.4572 0.4572)
			(layers "F.Cu" "F.Mask" "F.Paste")
			(net "PCIE_TX_CAP_N76")
		)
		(pad "AT22" smd circle
			(at 2.999994 16.999966 270)
			(size 0.4572 0.4572)
			(layers "F.Cu" "F.Mask" "F.Paste")
			(net "Net_309")
		)
		(pad "AT23" smd circle
			(at 3.999992 16.999966 270)
			(size 0.4572 0.4572)
			(layers "F.Cu" "F.Mask" "F.Paste")
			(net "PCIE_TX_CAP_N78")
		)
		(pad "AT24" smd circle
			(at 4.99999 16.999966 270)
			(size 0.4572 0.4572)
			(layers "F.Cu" "F.Mask" "F.Paste")
			(net "Net_310")
		)
		(pad "AT25" smd circle
			(at 5.999988 16.999966 270)
			(size 0.4572 0.4572)
			(layers "F.Cu" "F.Mask" "F.Paste")
			(net "GND")
		)
		(pad "AT26" smd circle
			(at 6.999986 16.999966 270)
			(size 0.4572 0.4572)
			(layers "F.Cu" "F.Mask" "F.Paste")
			(net "PCIE_TX_CAP_N80")
		)
		(pad "AT27" smd circle
			(at 7.999984 16.999966 270)
			(size 0.4572 0.4572)
			(layers "F.Cu" "F.Mask" "F.Paste")
			(net "PCIE_TX_CAP_P81")
		)
		(pad "AT28" smd circle
			(at 8.999982 16.999966 270)
			(size 0.4572 0.4572)
			(layers "F.Cu" "F.Mask" "F.Paste")
			(net "PCIE_TX_CAP_N82")
		)
		(pad "AT29" smd circle
			(at 9.99998 16.999966 270)
			(size 0.4572 0.4572)
			(layers "F.Cu" "F.Mask" "F.Paste")
			(net "PCIE_TX_CAP_P83")
		)
		(pad "AT30" smd circle
			(at 10.999978 16.999966 270)
			(size 0.4572 0.4572)
			(layers "F.Cu" "F.Mask" "F.Paste")
			(net "PCIE_TX_CAP_N84")
		)
		(pad "AT31" smd circle
			(at 11.999976 16.999966 270)
			(size 0.4572 0.4572)
			(layers "F.Cu" "F.Mask" "F.Paste")
			(net "PCIE_TX_CAP_P85")
		)
		(pad "AT32" smd circle
			(at 12.999974 16.999966 270)
			(size 0.4572 0.4572)
			(layers "F.Cu" "F.Mask" "F.Paste")
			(net "PCIE_TX_CAP_N86")
		)
		(pad "AT33" smd circle
			(at 13.999972 16.999966 270)
			(size 0.4572 0.4572)
			(layers "F.Cu" "F.Mask" "F.Paste")
			(net "PCIE_TX_CAP_P87")
		)
		(pad "AT34" smd circle
			(at 14.99997 16.999966 270)
			(size 0.4572 0.4572)
			(layers "F.Cu" "F.Mask" "F.Paste")
			(net "GND")
		)
		(pad "AT35" smd circle
			(at 15.999968 16.999966 270)
			(size 0.508 0.508)
			(layers "F.Cu" "F.Mask" "F.Paste")
			(net "GND")
		)
		(pad "AT36" smd circle
			(at 16.999966 16.999966 270)
			(size 0.508 0.508)
			(layers "F.Cu" "F.Mask" "F.Paste")
			(net "PCIE_TX_CAP_P89")
		)
		(pad "AT37" smd circle
			(at 17.999964 16.999966 270)
			(size 0.508 0.508)
			(layers "F.Cu" "F.Mask" "F.Paste")
			(net "PCIE_TX_CAP_N89")
		)
		(pad "AU2" smd circle
			(at -16.999966 17.999964 270)
			(size 0.508 0.508)
			(layers "F.Cu" "F.Mask" "F.Paste")
			(net "GND")
		)
		(pad "AU3" smd circle
			(at -15.999968 17.999964 270)
			(size 0.508 0.508)
			(layers "F.Cu" "F.Mask" "F.Paste")
			(net "GND")
		)
		(pad "AU4" smd circle
			(at -14.99997 17.999964 270)
			(size 0.4572 0.4572)
			(layers "F.Cu" "F.Mask" "F.Paste")
			(net "GND")
		)
		(pad "AU5" smd circle
			(at -13.999972 17.999964 270)
			(size 0.4572 0.4572)
			(layers "F.Cu" "F.Mask" "F.Paste")
			(net "GND")
		)
		(pad "AU6" smd circle
			(at -12.999974 17.999964 270)
			(size 0.4572 0.4572)
			(layers "F.Cu" "F.Mask" "F.Paste")
			(net "GND")
		)
		(pad "AU7" smd circle
			(at -11.999976 17.999964 270)
			(size 0.4572 0.4572)
			(layers "F.Cu" "F.Mask" "F.Paste")
			(net "GND")
		)
		(pad "AU9" smd circle
			(at -9.99998 17.999964 270)
			(size 0.4572 0.4572)
			(layers "F.Cu" "F.Mask" "F.Paste")
			(net "PCIE_TX_CAP_N65")
		)
		(pad "AU11" smd circle
			(at -7.999984 17.999964 270)
			(size 0.4572 0.4572)
			(layers "F.Cu" "F.Mask" "F.Paste")
			(net "PCIE_TX_CAP_N67")
		)
		(pad "AU13" smd circle
			(at -5.999988 17.999964 270)
			(size 0.4572 0.4572)
			(layers "F.Cu" "F.Mask" "F.Paste")
			(net "PCIE_TX_CAP_N69")
		)
		(pad "AU15" smd circle
			(at -3.999992 17.999964 270)
			(size 0.4572 0.4572)
			(layers "F.Cu" "F.Mask" "F.Paste")
			(net "PCIE_TX_CAP_N71")
		)
		(pad "AU16" smd circle
			(at -2.999994 17.999964 270)
			(size 0.4572 0.4572)
			(layers "F.Cu" "F.Mask" "F.Paste")
			(net "GND")
		)
		(pad "AU18" smd circle
			(at -0.999998 17.999964 270)
			(size 0.4572 0.4572)
			(layers "F.Cu" "F.Mask" "F.Paste")
			(net "PCIE_TX_CAP_N73")
		)
		(pad "AU20" smd circle
			(at 0.999998 17.999964 270)
			(size 0.4572 0.4572)
			(layers "F.Cu" "F.Mask" "F.Paste")
			(net "PCIE_TX_CAP_N75")
		)
		(pad "AU22" smd circle
			(at 2.999994 17.999964 270)
			(size 0.4572 0.4572)
			(layers "F.Cu" "F.Mask" "F.Paste")
			(net "Net_307")
		)
		(pad "AU24" smd circle
			(at 4.99999 17.999964 270)
			(size 0.4572 0.4572)
			(layers "F.Cu" "F.Mask" "F.Paste")
			(net "Net_308")
		)
		(pad "AU25" smd circle
			(at 5.999988 17.999964 270)
			(size 0.4572 0.4572)
			(layers "F.Cu" "F.Mask" "F.Paste")
			(net "GND")
		)
		(pad "AU27" smd circle
			(at 7.999984 17.999964 270)
			(size 0.4572 0.4572)
			(layers "F.Cu" "F.Mask" "F.Paste")
			(net "PCIE_TX_CAP_N81")
		)
		(pad "AU29" smd circle
			(at 9.99998 17.999964 270)
			(size 0.4572 0.4572)
			(layers "F.Cu" "F.Mask" "F.Paste")
			(net "PCIE_TX_CAP_N83")
		)
		(pad "AU31" smd circle
			(at 11.999976 17.999964 270)
			(size 0.4572 0.4572)
			(layers "F.Cu" "F.Mask" "F.Paste")
			(net "PCIE_TX_CAP_N85")
		)
		(pad "AU33" smd circle
			(at 13.999972 17.999964 270)
			(size 0.4572 0.4572)
			(layers "F.Cu" "F.Mask" "F.Paste")
			(net "PCIE_TX_CAP_N87")
		)
		(pad "AU34" smd circle
			(at 14.99997 17.999964 270)
			(size 0.4572 0.4572)
			(layers "F.Cu" "F.Mask" "F.Paste")
			(net "GND")
		)
		(pad "AU35" smd circle
			(at 15.999968 17.999964 270)
			(size 0.508 0.508)
			(layers "F.Cu" "F.Mask" "F.Paste")
			(net "PCIE_TX_CAP_P88")
		)
		(pad "AU36" smd circle
			(at 16.999966 17.999964 270)
			(size 0.508 0.508)
			(layers "F.Cu" "F.Mask" "F.Paste")
			(net "PCIE_TX_CAP_N88")
		)
		(pad "B1" smd circle
			(at -17.999964 -16.999966 270)
			(size 0.508 0.508)
			(layers "F.Cu" "F.Mask" "F.Paste")
			(net "PCIE_TX_CAP_N32")
		)
		(pad "B2" smd circle
			(at -16.999966 -16.999966 270)
			(size 0.508 0.508)
			(layers "F.Cu" "F.Mask" "F.Paste")
			(net "PCIE_TX_CAP_P32")
		)
		(pad "B3" smd circle
			(at -15.999968 -16.999966 270)
			(size 0.508 0.508)
			(layers "F.Cu" "F.Mask" "F.Paste")
			(net "GND")
		)
		(pad "B4" smd circle
			(at -14.99997 -16.999966 270)
			(size 0.4572 0.4572)
			(layers "F.Cu" "F.Mask" "F.Paste")
			(net "PCIE_RX_N32")
		)
		(pad "B5" smd circle
			(at -13.999972 -16.999966 270)
			(size 0.4572 0.4572)
			(layers "F.Cu" "F.Mask" "F.Paste")
			(net "PCIE_RX_P32")
		)
		(pad "B6" smd circle
			(at -12.999974 -16.999966 270)
			(size 0.4572 0.4572)
			(layers "F.Cu" "F.Mask" "F.Paste")
			(net "GND")
		)
		(pad "B7" smd circle
			(at -11.999976 -16.999966 270)
			(size 0.4572 0.4572)
			(layers "F.Cu" "F.Mask" "F.Paste")
			(net "GND")
		)
		(pad "B8" smd circle
			(at -10.999978 -16.999966 270)
			(size 0.4572 0.4572)
			(layers "F.Cu" "F.Mask" "F.Paste")
			(net "PCIE_TX_CAP_N31")
		)
		(pad "B9" smd circle
			(at -9.99998 -16.999966 270)
			(size 0.4572 0.4572)
			(layers "F.Cu" "F.Mask" "F.Paste")
			(net "PCIE_TX_CAP_P30")
		)
		(pad "B10" smd circle
			(at -8.999982 -16.999966 270)
			(size 0.4572 0.4572)
			(layers "F.Cu" "F.Mask" "F.Paste")
			(net "PCIE_TX_CAP_N29")
		)
		(pad "B11" smd circle
			(at -7.999984 -16.999966 270)
			(size 0.4572 0.4572)
			(layers "F.Cu" "F.Mask" "F.Paste")
			(net "PCIE_TX_CAP_P28")
		)
		(pad "B12" smd circle
			(at -6.999986 -16.999966 270)
			(size 0.4572 0.4572)
			(layers "F.Cu" "F.Mask" "F.Paste")
			(net "PCIE_TX_CAP_N27")
		)
		(pad "B13" smd circle
			(at -5.999988 -16.999966 270)
			(size 0.4572 0.4572)
			(layers "F.Cu" "F.Mask" "F.Paste")
			(net "PCIE_TX_CAP_P26")
		)
		(pad "B14" smd circle
			(at -4.99999 -16.999966 270)
			(size 0.4572 0.4572)
			(layers "F.Cu" "F.Mask" "F.Paste")
			(net "PCIE_TX_CAP_N25")
		)
		(pad "B15" smd circle
			(at -3.999992 -16.999966 270)
			(size 0.4572 0.4572)
			(layers "F.Cu" "F.Mask" "F.Paste")
			(net "PCIE_TX_CAP_P24")
		)
		(pad "B16" smd circle
			(at -2.999994 -16.999966 270)
			(size 0.4572 0.4572)
			(layers "F.Cu" "F.Mask" "F.Paste")
			(net "GND")
		)
		(pad "B17" smd circle
			(at -1.999996 -16.999966 270)
			(size 0.4572 0.4572)
			(layers "F.Cu" "F.Mask" "F.Paste")
			(net "PCIE_TX_CAP_N23")
		)
		(pad "B18" smd circle
			(at -0.999998 -16.999966 270)
			(size 0.4572 0.4572)
			(layers "F.Cu" "F.Mask" "F.Paste")
			(net "PCIE_TX_CAP_P22")
		)
		(pad "B19" smd circle
			(at 0 -16.999966 270)
			(size 0.4572 0.4572)
			(layers "F.Cu" "F.Mask" "F.Paste")
			(net "PCIE_TX_CAP_N21")
		)
		(pad "B20" smd circle
			(at 0.999998 -16.999966 270)
			(size 0.4572 0.4572)
			(layers "F.Cu" "F.Mask" "F.Paste")
			(net "PCIE_TX_CAP_P20")
		)
		(pad "B21" smd circle
			(at 1.999996 -16.999966 270)
			(size 0.4572 0.4572)
			(layers "F.Cu" "F.Mask" "F.Paste")
			(net "PCIE_TX_CAP_N19")
		)
		(pad "B22" smd circle
			(at 2.999994 -16.999966 270)
			(size 0.4572 0.4572)
			(layers "F.Cu" "F.Mask" "F.Paste")
			(net "PCIE_TX_CAP_P18")
		)
		(pad "B23" smd circle
			(at 3.999992 -16.999966 270)
			(size 0.4572 0.4572)
			(layers "F.Cu" "F.Mask" "F.Paste")
			(net "PCIE_TX_CAP_N17")
		)
		(pad "B24" smd circle
			(at 4.99999 -16.999966 270)
			(size 0.4572 0.4572)
			(layers "F.Cu" "F.Mask" "F.Paste")
			(net "PCIE_TX_CAP_P16")
		)
		(pad "B25" smd circle
			(at 5.999988 -16.999966 270)
			(size 0.4572 0.4572)
			(layers "F.Cu" "F.Mask" "F.Paste")
			(net "GND")
		)
		(pad "B26" smd circle
			(at 6.999986 -16.999966 270)
			(size 0.4572 0.4572)
			(layers "F.Cu" "F.Mask" "F.Paste")
			(net "PCIE_TX_CAP_N15")
		)
		(pad "B27" smd circle
			(at 7.999984 -16.999966 270)
			(size 0.4572 0.4572)
			(layers "F.Cu" "F.Mask" "F.Paste")
			(net "PCIE_TX_CAP_P14")
		)
		(pad "B28" smd circle
			(at 8.999982 -16.999966 270)
			(size 0.4572 0.4572)
			(layers "F.Cu" "F.Mask" "F.Paste")
			(net "PCIE_TX_CAP_N13")
		)
		(pad "B29" smd circle
			(at 9.99998 -16.999966 270)
			(size 0.4572 0.4572)
			(layers "F.Cu" "F.Mask" "F.Paste")
			(net "PCIE_TX_CAP_P12")
		)
		(pad "B30" smd circle
			(at 10.999978 -16.999966 270)
			(size 0.4572 0.4572)
			(layers "F.Cu" "F.Mask" "F.Paste")
			(net "PCIE_TX_CAP_N11")
		)
		(pad "B31" smd circle
			(at 11.999976 -16.999966 270)
			(size 0.4572 0.4572)
			(layers "F.Cu" "F.Mask" "F.Paste")
			(net "PCIE_TX_CAP_P10")
		)
		(pad "B32" smd circle
			(at 12.999974 -16.999966 270)
			(size 0.4572 0.4572)
			(layers "F.Cu" "F.Mask" "F.Paste")
			(net "PCIE_TX_CAP_N9")
		)
		(pad "B33" smd circle
			(at 13.999972 -16.999966 270)
			(size 0.4572 0.4572)
			(layers "F.Cu" "F.Mask" "F.Paste")
			(net "PCIE_TX_CAP_P8")
		)
		(pad "B34" smd circle
			(at 14.99997 -16.999966 270)
			(size 0.4572 0.4572)
			(layers "F.Cu" "F.Mask" "F.Paste")
			(net "GND")
		)
		(pad "B35" smd circle
			(at 15.999968 -16.999966 270)
			(size 0.508 0.508)
			(layers "F.Cu" "F.Mask" "F.Paste")
			(net "GND")
		)
		(pad "B36" smd circle
			(at 16.999966 -16.999966 270)
			(size 0.508 0.508)
			(layers "F.Cu" "F.Mask" "F.Paste")
			(net "PCIE_TX_CAP_P6")
		)
		(pad "B37" smd circle
			(at 17.999964 -16.999966 270)
			(size 0.508 0.508)
			(layers "F.Cu" "F.Mask" "F.Paste")
			(net "PCIE_TX_CAP_N6")
		)
		(pad "C2" smd circle
			(at -16.999966 -15.999968 270)
			(size 0.508 0.508)
			(layers "F.Cu" "F.Mask" "F.Paste")
			(net "PCIE_TX_CAP_N33")
		)
		(pad "C3" smd circle
			(at -15.999968 -15.999968 270)
			(size 0.508 0.508)
			(layers "F.Cu" "F.Mask" "F.Paste")
			(net "PCIE_TX_CAP_P33")
		)
		(pad "C4" smd circle
			(at -14.99997 -15.999968 270)
			(size 0.4572 0.4572)
			(layers "F.Cu" "F.Mask" "F.Paste")
			(net "GND")
		)
		(pad "C5" smd circle
			(at -13.999972 -15.999968 270)
			(size 0.4572 0.4572)
			(layers "F.Cu" "F.Mask" "F.Paste")
			(net "PCIE_RX_N33")
		)
		(pad "C6" smd circle
			(at -12.999974 -15.999968 270)
			(size 0.4572 0.4572)
			(layers "F.Cu" "F.Mask" "F.Paste")
			(net "PCIE_RX_P33")
		)
		(pad "C7" smd circle
			(at -11.999976 -15.999968 270)
			(size 0.4572 0.4572)
			(layers "F.Cu" "F.Mask" "F.Paste")
			(net "GND")
		)
		(pad "C8" smd circle
			(at -10.999978 -15.999968 270)
			(size 0.4572 0.4572)
			(layers "F.Cu" "F.Mask" "F.Paste")
			(net "PCIE_TX_CAP_P31")
		)
		(pad "C9" smd circle
			(at -9.99998 -15.999968 270)
			(size 0.4572 0.4572)
			(layers "F.Cu" "F.Mask" "F.Paste")
			(net "GND")
		)
		(pad "C10" smd circle
			(at -8.999982 -15.999968 270)
			(size 0.4572 0.4572)
			(layers "F.Cu" "F.Mask" "F.Paste")
			(net "PCIE_TX_CAP_P29")
		)
		(pad "C11" smd circle
			(at -7.999984 -15.999968 270)
			(size 0.4572 0.4572)
			(layers "F.Cu" "F.Mask" "F.Paste")
			(net "GND")
		)
		(pad "C12" smd circle
			(at -6.999986 -15.999968 270)
			(size 0.4572 0.4572)
			(layers "F.Cu" "F.Mask" "F.Paste")
			(net "PCIE_TX_CAP_P27")
		)
		(pad "C13" smd circle
			(at -5.999988 -15.999968 270)
			(size 0.4572 0.4572)
			(layers "F.Cu" "F.Mask" "F.Paste")
			(net "GND")
		)
		(pad "C14" smd circle
			(at -4.99999 -15.999968 270)
			(size 0.4572 0.4572)
			(layers "F.Cu" "F.Mask" "F.Paste")
			(net "PCIE_TX_CAP_P25")
		)
		(pad "C15" smd circle
			(at -3.999992 -15.999968 270)
			(size 0.4572 0.4572)
			(layers "F.Cu" "F.Mask" "F.Paste")
			(net "GND")
		)
		(pad "C16" smd circle
			(at -2.999994 -15.999968 270)
			(size 0.4572 0.4572)
			(layers "F.Cu" "F.Mask" "F.Paste")
			(net "GND")
		)
		(pad "C17" smd circle
			(at -1.999996 -15.999968 270)
			(size 0.4572 0.4572)
			(layers "F.Cu" "F.Mask" "F.Paste")
			(net "PCIE_TX_CAP_P23")
		)
		(pad "C18" smd circle
			(at -0.999998 -15.999968 270)
			(size 0.4572 0.4572)
			(layers "F.Cu" "F.Mask" "F.Paste")
			(net "GND")
		)
		(pad "C19" smd circle
			(at 0 -15.999968 270)
			(size 0.4572 0.4572)
			(layers "F.Cu" "F.Mask" "F.Paste")
			(net "PCIE_TX_CAP_P21")
		)
		(pad "C20" smd circle
			(at 0.999998 -15.999968 270)
			(size 0.4572 0.4572)
			(layers "F.Cu" "F.Mask" "F.Paste")
			(net "GND")
		)
		(pad "C21" smd circle
			(at 1.999996 -15.999968 270)
			(size 0.4572 0.4572)
			(layers "F.Cu" "F.Mask" "F.Paste")
			(net "PCIE_TX_CAP_P19")
		)
		(pad "C22" smd circle
			(at 2.999994 -15.999968 270)
			(size 0.4572 0.4572)
			(layers "F.Cu" "F.Mask" "F.Paste")
			(net "GND")
		)
		(pad "C23" smd circle
			(at 3.999992 -15.999968 270)
			(size 0.4572 0.4572)
			(layers "F.Cu" "F.Mask" "F.Paste")
			(net "PCIE_TX_CAP_P17")
		)
		(pad "C24" smd circle
			(at 4.99999 -15.999968 270)
			(size 0.4572 0.4572)
			(layers "F.Cu" "F.Mask" "F.Paste")
			(net "GND")
		)
		(pad "C25" smd circle
			(at 5.999988 -15.999968 270)
			(size 0.4572 0.4572)
			(layers "F.Cu" "F.Mask" "F.Paste")
			(net "GND")
		)
		(pad "C26" smd circle
			(at 6.999986 -15.999968 270)
			(size 0.4572 0.4572)
			(layers "F.Cu" "F.Mask" "F.Paste")
			(net "PCIE_TX_CAP_P15")
		)
		(pad "C27" smd circle
			(at 7.999984 -15.999968 270)
			(size 0.4572 0.4572)
			(layers "F.Cu" "F.Mask" "F.Paste")
			(net "GND")
		)
		(pad "C28" smd circle
			(at 8.999982 -15.999968 270)
			(size 0.4572 0.4572)
			(layers "F.Cu" "F.Mask" "F.Paste")
			(net "PCIE_TX_CAP_P13")
		)
		(pad "C29" smd circle
			(at 9.99998 -15.999968 270)
			(size 0.4572 0.4572)
			(layers "F.Cu" "F.Mask" "F.Paste")
			(net "GND")
		)
		(pad "C30" smd circle
			(at 10.999978 -15.999968 270)
			(size 0.4572 0.4572)
			(layers "F.Cu" "F.Mask" "F.Paste")
			(net "PCIE_TX_CAP_P11")
		)
		(pad "C31" smd circle
			(at 11.999976 -15.999968 270)
			(size 0.4572 0.4572)
			(layers "F.Cu" "F.Mask" "F.Paste")
			(net "GND")
		)
		(pad "C32" smd circle
			(at 12.999974 -15.999968 270)
			(size 0.4572 0.4572)
			(layers "F.Cu" "F.Mask" "F.Paste")
			(net "PCIE_TX_CAP_P9")
		)
		(pad "C33" smd circle
			(at 13.999972 -15.999968 270)
			(size 0.4572 0.4572)
			(layers "F.Cu" "F.Mask" "F.Paste")
			(net "GND")
		)
		(pad "C34" smd circle
			(at 14.99997 -15.999968 270)
			(size 0.4572 0.4572)
			(layers "F.Cu" "F.Mask" "F.Paste")
			(net "GND")
		)
		(pad "C35" smd circle
			(at 15.999968 -15.999968 270)
			(size 0.508 0.508)
			(layers "F.Cu" "F.Mask" "F.Paste")
			(net "PCIE_TX_CAP_P5")
		)
		(pad "C36" smd circle
			(at 16.999966 -15.999968 270)
			(size 0.508 0.508)
			(layers "F.Cu" "F.Mask" "F.Paste")
			(net "PCIE_TX_CAP_N5")
		)
		(pad "D1" smd circle
			(at -17.999964 -14.99997 270)
			(size 0.4572 0.4572)
			(layers "F.Cu" "F.Mask" "F.Paste")
			(net "PCIE_TX_CAP_N34")
		)
		(pad "D2" smd circle
			(at -16.999966 -14.99997 270)
			(size 0.4572 0.4572)
			(layers "F.Cu" "F.Mask" "F.Paste")
			(net "PCIE_TX_CAP_P34")
		)
	)
)
